FILE_TYPE = CONNECTIVITY;
{Allegro Design Entry HDL 17.2-2016 S081 (4005846) 1/11/2022}
"PAGE_NUMBER" = 145;
0"NC";
END.
